# TIMECARD (Time Appliance Project (Time Card)) — schematic netlist excerpt (pin names and nets, part order shuffled) for the footprints in the layout excerpt that follows; sources: Cadence DE-HDL packaged netlist, KiCad conversion of R4006-B0001-02_R01.brd

U16  74HCT2G125DP_TSSOP8  NC7WV125K8X  pkg SOP8_091_P0197_H035  page 23
  \1oe*\  = SMA2_SIG_OUT_BF_EN_N
  \1a\  = UNNAMED_12_74HCT2G125DPTSSOP8_9
  \2y\  = BF_ANT2_IN
  GND  = SG
  \2a\  = BF_SMA2_SIG_IO_CONN
  \1y\  = BF_SMA2_SIG_IO_CONN
  \2oe*\  = SMA2_SIG_IN_BF_EN_N
  VCC  = XP3R3V_FPGA

(kicad_pcb
	(version 20260206)
	(generator "pcbnew")
	(generator_version "10.0")
	(general
		(thickness 1.6)
		(legacy_teardrops no)
	)
	(paper "A4")
	(title_block
		(title "timecard-production-celestica-r4006 — R4006-B0001-02_R01.brd")
		(comment 1 "Time Appliance Project (Time Card) / footprints 651-651 of 1113")
	)
	(layers
		(0 "F.Cu" signal "TOP")
		(4 "In1.Cu" signal "L02_GND1")
		(6 "In2.Cu" signal "L03_SIG1")
		(8 "In3.Cu" signal "L04_GND2")
		(10 "In4.Cu" signal "L05_VCC1")
		(12 "In5.Cu" signal "L06_VCC2")
		(14 "In6.Cu" signal "L07_GND3")
		(16 "In7.Cu" signal "L08_SIG2")
		(18 "In8.Cu" signal "L09_GND4")
		(2 "B.Cu" signal "BOTTOM")
		(9 "F.Adhes" user "F.Adhesive")
		(11 "B.Adhes" user "B.Adhesive")
		(13 "F.Paste" user "Package Geometry/Pastemask Top")
		(15 "B.Paste" user "Package Geometry/Pastemask Bottom")
		(5 "F.SilkS" user "Ref Des/Silkscreen Top")
		(7 "B.SilkS" user "Ref Des/Silkscreen Bottom")
		(1 "F.Mask" user "Board Geometry/Soldermask Top")
		(3 "B.Mask" user "Board Geometry/Soldermask Bottom")
		(17 "Dwgs.User" user "User.Drawings")
		(19 "Cmts.User" user "User.Comments")
		(21 "Eco1.User" user "User.Eco1")
		(23 "Eco2.User" user "User.Eco2")
		(25 "Edge.Cuts" user "Board Geometry/Outline")
		(27 "Margin" user)
		(31 "F.CrtYd" user "Package Geometry/Place Bound Top")
		(29 "B.CrtYd" user "Package Geometry/Place Bound Bottom")
		(35 "F.Fab" user "Ref Des/Assembly Top")
		(33 "B.Fab" user "Ref Des/Assembly Bottom")
	)
	(footprint ""
		(layer "F.Cu")
		(at 13.899896 -47.099982 -90)
		(property "Reference" "U16"
			(at -0.906018 2.049526 90)
			(unlocked yes)
			(layer "F.SilkS")
			(effects
				(font
					(size 0.7874 0.5842)
					(thickness 0.1524)
				)
			)
		)
		(property "Value" ""
			(at 0 0 270)
			(layer "F.Fab")
			(effects
				(font
					(size 1.27 1.27)
				)
			)
		)
		(property "Device Type" "74HCT2G125DP_TSSOP8-G220-00055A"
			(at 0 2.413 270)
			(unlocked yes)
			(layer "F.Fab")
			(hide yes)
			(effects
				(font
					(size 0.7874 0.5842)
					(thickness 0.1524)
				)
			)
		)
		(property "User Part Number" "PARTNUM*"
			(at 0 3.6068 270)
			(unlocked yes)
			(layer "Cmts.User")
			(hide yes)
			(effects
				(font
					(size 0.7874 0.5842)
					(thickness 0.1524)
				)
			)
		)
		(duplicate_pad_numbers_are_jumpers no)
		(fp_line
			(start -2.426716 1.304036)
			(end -2.426716 -1.304036)
			(stroke
				(width 0.1)
				(type default)
			)
			(layer "F.SilkS")
		)
		(fp_line
			(start 2.426716 1.304036)
			(end -2.426716 1.304036)
			(stroke
				(width 0.1)
				(type default)
			)
			(layer "F.SilkS")
		)
		(fp_line
			(start -2.426716 -1.304036)
			(end 2.426716 -1.304036)
			(stroke
				(width 0.1)
				(type default)
			)
			(layer "F.SilkS")
		)
		(fp_line
			(start 2.426716 -1.304036)
			(end 2.426716 1.304036)
			(stroke
				(width 0.1)
				(type default)
			)
			(layer "F.SilkS")
		)
		(fp_poly
			(pts
				(arc
					(start -3.21437 -1.465326)
					(mid -3.21437 -0.703326)
					(end -3.21437 -1.465326)
				)
			)
			(stroke
				(width 0)
				(type default)
			)
			(fill yes)
			(layer "F.SilkS")
		)
		(fp_poly
			(pts
				(xy -2.680716 1.558036) (xy 2.680716 1.558036) (xy 2.680716 -1.558036) (xy -2.680716 -1.558036)
			)
			(stroke
				(width 0)
				(type default)
			)
			(fill no)
			(layer "F.CrtYd")
		)
		(fp_line
			(start -1.199896 1.050036)
			(end 1.199896 1.050036)
			(stroke
				(width 0.1)
				(type default)
			)
			(layer "F.Fab")
		)
		(fp_line
			(start 1.199896 1.050036)
			(end 1.199896 -1.050036)
			(stroke
				(width 0.1)
				(type default)
			)
			(layer "F.Fab")
		)
		(fp_line
			(start -1.199896 -1.050036)
			(end -1.199896 1.050036)
			(stroke
				(width 0.1)
				(type default)
			)
			(layer "F.Fab")
		)
		(fp_line
			(start 1.199896 -1.050036)
			(end -1.199896 -1.050036)
			(stroke
				(width 0.1)
				(type default)
			)
			(layer "F.Fab")
		)
		(fp_poly
			(pts
				(arc
					(start -1.922018 -1.721104)
					(mid -1.922018 -0.959104)
					(end -1.922018 -1.721104)
				)
			)
			(stroke
				(width 0)
				(type default)
			)
			(fill yes)
			(layer "F.Fab")
		)
		(fp_text user "5"
			(at 2.884932 1.580896 0)
			(unlocked yes)
			(layer "F.SilkS")
			(effects
				(font
					(size 0.635 0.4064)
					(thickness 0.1524)
				)
			)
		)
		(fp_text user "4"
			(at -2.957068 1.326896 0)
			(unlocked yes)
			(layer "F.SilkS")
			(effects
				(font
					(size 0.635 0.4064)
					(thickness 0.1524)
				)
			)
		)
		(fp_text user "8"
			(at 1.919732 -1.721104 0)
			(unlocked yes)
			(layer "F.SilkS")
			(effects
				(font
					(size 0.635 0.4064)
					(thickness 0.1524)
				)
			)
		)
		(fp_text user "4"
			(at -1.755648 1.326896 0)
			(unlocked yes)
			(layer "F.Fab")
			(effects
				(font
					(size 0.7874 0.5842)
					(thickness 0.1524)
				)
			)
		)
		(fp_text user "5"
			(at 2.181352 1.199896 0)
			(unlocked yes)
			(layer "F.Fab")
			(effects
				(font
					(size 0.7874 0.5842)
					(thickness 0.1524)
				)
			)
		)
		(fp_text user "8"
			(at 2.054352 -1.594104 0)
			(unlocked yes)
			(layer "F.Fab")
			(effects
				(font
					(size 0.7874 0.5842)
					(thickness 0.1524)
				)
			)
		)
		(pad "1" smd rect
			(at -1.690116 -0.749808 270)
			(size 0.9652 0.3048)
			(layers "F.Cu" "F.Mask" "F.Paste")
			(net "SMA2_SIG_OUT_BF_EN_N")
		)
		(pad "2" smd rect
			(at -1.690116 -0.249936 270)
			(size 0.9652 0.3048)
			(layers "F.Cu" "F.Mask" "F.Paste")
			(net "UNNAMED_12_74HCT2G125DPTSSOP8_9")
		)
		(pad "3" smd rect
			(at -1.690116 0.249936 270)
			(size 0.9652 0.3048)
			(layers "F.Cu" "F.Mask" "F.Paste")
			(net "BF_ANT2_IN")
		)
		(pad "4" smd rect
			(at -1.690116 0.749808 270)
			(size 0.9652 0.3048)
			(layers "F.Cu" "F.Mask" "F.Paste")
			(net "SG")
		)
		(pad "5" smd rect
			(at 1.690116 0.749808 270)
			(size 0.9652 0.3048)
			(layers "F.Cu" "F.Mask" "F.Paste")
			(net "BF_SMA2_SIG_IO_CONN")
		)
		(pad "6" smd rect
			(at 1.690116 0.249936 270)
			(size 0.9652 0.3048)
			(layers "F.Cu" "F.Mask" "F.Paste")
			(net "BF_SMA2_SIG_IO_CONN")
		)
		(pad "7" smd rect
			(at 1.690116 -0.249936 270)
			(size 0.9652 0.3048)
			(layers "F.Cu" "F.Mask" "F.Paste")
			(net "SMA2_SIG_IN_BF_EN_N")
		)
		(pad "8" smd rect
			(at 1.690116 -0.749808 270)
			(size 0.9652 0.3048)
			(layers "F.Cu" "F.Mask" "F.Paste")
			(net "XP3R3V_FPGA")
		)
	)
)
